(kicad_pcb
	(version 20260206)
	(generator "pcbnew")
	(generator_version "10.0")
	(general
		(thickness 1.6)
		(legacy_teardrops no)
	)
	(paper "A4")
	(title_block
		(title "Bryce Canyon_IOM_M2_16342-2_OCP.brd")
		(comment 1 "Bryce Canyon / footprints 595-598 of 1146")
	)
	(layers
		(0 "F.Cu" signal "TOP")
		(4 "In1.Cu" signal "L2GND")
		(6 "In2.Cu" signal "L3")
		(8 "In3.Cu" signal "L4VCC")
		(10 "In4.Cu" signal "L5VCC")
		(12 "In5.Cu" signal "L6")
		(14 "In6.Cu" signal "L7GND")
		(2 "B.Cu" signal "BOTTOM")
		(9 "F.Adhes" user "F.Adhesive")
		(11 "B.Adhes" user "B.Adhesive")
		(13 "F.Paste" user "Package Geometry/Pastemask Top")
		(15 "B.Paste" user "Package Geometry/Pastemask Bottom")
		(5 "F.SilkS" user "Ref Des/Silkscreen Top")
		(7 "B.SilkS" user "Ref Des/Silkscreen Bottom")
		(1 "F.Mask" user "Board Geometry/Soldermask Top")
		(3 "B.Mask" user "Board Geometry/Soldermask Bottom")
		(17 "Dwgs.User" user "User.Drawings")
		(19 "Cmts.User" user "User.Comments")
		(21 "Eco1.User" user "User.Eco1")
		(23 "Eco2.User" user "User.Eco2")
		(25 "Edge.Cuts" user "Board Geometry/Outline")
		(27 "Margin" user)
		(31 "F.CrtYd" user "Package Geometry/Place Bound Top")
		(29 "B.CrtYd" user "Package Geometry/Place Bound Bottom")
		(35 "F.Fab" user "Ref Des/Assembly Top")
		(33 "B.Fab" user "Ref Des/Assembly Bottom")
	)
	(footprint ""
		(layer "F.Cu")
		(at 92.751656 -155.60548 90)
		(property "Reference" "U99"
			(at 0 0 90)
			(layer "F.SilkS")
			(hide yes)
			(effects
				(font
					(size 1.27 1.27)
				)
			)
		)
		(property "Value" "USB2514B-AEZC-TR-GP-U"
			(at -5.5372 -5.2832 90)
			(unlocked yes)
			(layer "F.Fab")
			(hide yes)
			(effects
				(font
					(size 1.016 1.016)
					(thickness 0.1524)
				)
			)
		)
		(property "Device Type" "QFN36-G3D85H40"
			(at -5.5372 -6.8072 90)
			(unlocked yes)
			(layer "F.Fab")
			(hide yes)
			(effects
				(font
					(size 1.016 1.016)
					(thickness 0.1524)
				)
			)
		)
		(duplicate_pad_numbers_are_jumpers no)
		(fp_line
			(start -4.0132 -4.0132)
			(end -2.7432 -4.0132)
			(stroke
				(width 0.1524)
				(type default)
			)
			(layer "F.SilkS")
		)
		(fp_line
			(start -0.0254 -3.7846)
			(end -0.0254 -4.2926)
			(stroke
				(width 0.1524)
				(type default)
			)
			(layer "F.SilkS")
		)
		(fp_line
			(start -4.0132 -2.7432)
			(end -4.0132 -4.0132)
			(stroke
				(width 0.1524)
				(type default)
			)
			(layer "F.SilkS")
		)
		(fp_line
			(start -3.7846 -2.0066)
			(end -4.4704 -2.0066)
			(stroke
				(width 0.1524)
				(type default)
			)
			(layer "F.SilkS")
		)
		(fp_line
			(start 4.3434 -1.524)
			(end 3.8608 -1.524)
			(stroke
				(width 0.1524)
				(type default)
			)
			(layer "F.SilkS")
		)
		(fp_line
			(start -3.8608 0.4826)
			(end -4.318 0.4826)
			(stroke
				(width 0.1524)
				(type default)
			)
			(layer "F.SilkS")
		)
		(fp_line
			(start 4.4958 0.9652)
			(end 3.81 0.9652)
			(stroke
				(width 0.1524)
				(type default)
			)
			(layer "F.SilkS")
		)
		(fp_line
			(start -1.4986 3.8354)
			(end -1.4986 4.445)
			(stroke
				(width 0.1524)
				(type default)
			)
			(layer "F.SilkS")
		)
		(fp_line
			(start 4.0132 4.0132)
			(end 4.0132 2.7432)
			(stroke
				(width 0.1524)
				(type default)
			)
			(layer "F.SilkS")
		)
		(fp_line
			(start 2.7432 4.0132)
			(end 4.0132 4.0132)
			(stroke
				(width 0.1524)
				(type default)
			)
			(layer "F.SilkS")
		)
		(fp_line
			(start -2.7432 4.0132)
			(end -4.0132 4.0132)
			(stroke
				(width 0.1524)
				(type default)
			)
			(layer "F.SilkS")
		)
		(fp_line
			(start -4.0132 4.0132)
			(end -4.0132 2.7432)
			(stroke
				(width 0.1524)
				(type default)
			)
			(layer "F.SilkS")
		)
		(fp_line
			(start 0.9906 4.318)
			(end 0.9906 3.81)
			(stroke
				(width 0.1524)
				(type default)
			)
			(layer "F.SilkS")
		)
		(fp_poly
			(pts
				(xy 2.7432 -4.0132) (xy 4.0132 -2.7432) (xy 4.0132 -4.0132)
			)
			(stroke
				(width 0)
				(type default)
			)
			(fill yes)
			(layer "F.SilkS")
		)
		(fp_rect
			(start -4.0132 4.0132)
			(end 4.0132 -4.0132)
			(stroke
				(width 0)
				(type default)
			)
			(fill no)
			(layer "F.CrtYd")
		)
		(fp_rect
			(start -4.0132 4.0132)
			(end 4.0132 -4.0132)
			(stroke
				(width 0)
				(type default)
			)
			(fill no)
			(layer "F.Fab")
		)
		(pad "1" smd rect
			(at 1.999996 -2.9591 90)
			(size 0.3048 1.0922)
			(layers "F.Cu" "F.Mask" "F.Paste")
			(net "USB_P1_DN")
		)
		(pad "2" smd rect
			(at 1.500124 -2.8702 90)
			(size 0.3048 1.27)
			(layers "F.Cu" "F.Mask" "F.Paste")
			(net "USB_P1_DP")
		)
		(pad "3" smd rect
			(at 0.999998 -2.8702 90)
			(size 0.3048 1.27)
			(layers "F.Cu" "F.Mask" "F.Paste")
			(net "USB_P2_DN")
		)
		(pad "4" smd rect
			(at 0.500126 -2.8702 90)
			(size 0.3048 1.27)
			(layers "F.Cu" "F.Mask" "F.Paste")
			(net "USB_P2_DP")
		)
		(pad "5" smd rect
			(at 0 -2.8702 90)
			(size 0.3048 1.27)
			(layers "F.Cu" "F.Mask" "F.Paste")
			(net "P3V3_STBY")
		)
		(pad "6" smd rect
			(at -0.500126 -2.8702 90)
			(size 0.3048 1.27)
			(layers "F.Cu" "F.Mask" "F.Paste")
			(net "USB_P3_DN")
		)
		(pad "7" smd rect
			(at -0.999998 -2.8702 90)
			(size 0.3048 1.27)
			(layers "F.Cu" "F.Mask" "F.Paste")
			(net "USB_P3_DP")
		)
		(pad "8" smd rect
			(at -1.500124 -2.8702 90)
			(size 0.3048 1.27)
			(layers "F.Cu" "F.Mask" "F.Paste")
			(net "Net_109")
		)
		(pad "9" smd rect
			(at -1.999996 -2.9591 90)
			(size 0.3048 1.0922)
			(layers "F.Cu" "F.Mask" "F.Paste")
			(net "Net_110")
		)
		(pad "10" smd rect
			(at -2.9591 -1.999996 90)
			(size 1.0922 0.3048)
			(layers "F.Cu" "F.Mask" "F.Paste")
			(net "P3V3_STBY")
		)
		(pad "11" smd rect
			(at -2.8702 -1.500124 90)
			(size 1.27 0.3048)
			(layers "F.Cu" "F.Mask" "F.Paste")
			(net "GND")
		)
		(pad "12" smd rect
			(at -2.8702 -0.999998 90)
			(size 1.27 0.3048)
			(layers "F.Cu" "F.Mask" "F.Paste")
			(net "USB_EN_1")
		)
		(pad "13" smd rect
			(at -2.8702 -0.500126 90)
			(size 1.27 0.3048)
			(layers "F.Cu" "F.Mask" "F.Paste")
			(net "USB_OCS_N1")
		)
		(pad "14" smd rect
			(at -2.8702 0 90)
			(size 1.27 0.3048)
			(layers "F.Cu" "F.Mask" "F.Paste")
			(net "CRFILT")
		)
		(pad "15" smd rect
			(at -2.8702 0.500126 90)
			(size 1.27 0.3048)
			(layers "F.Cu" "F.Mask" "F.Paste")
			(net "P3V3_STBY")
		)
		(pad "16" smd rect
			(at -2.8702 0.999998 90)
			(size 1.27 0.3048)
			(layers "F.Cu" "F.Mask" "F.Paste")
			(net "USB_EN_2")
		)
		(pad "17" smd rect
			(at -2.8702 1.500124 90)
			(size 1.27 0.3048)
			(layers "F.Cu" "F.Mask" "F.Paste")
			(net "USB_OCS_N2")
		)
		(pad "18" smd rect
			(at -2.9591 1.999996 90)
			(size 1.0922 0.3048)
			(layers "F.Cu" "F.Mask" "F.Paste")
			(net "USB_EN_3")
		)
		(pad "19" smd rect
			(at -1.999996 2.9591 90)
			(size 0.3048 1.0922)
			(layers "F.Cu" "F.Mask" "F.Paste")
			(net "USB_OCS_N3")
		)
		(pad "20" smd rect
			(at -1.500124 2.8702 90)
			(size 0.3048 1.27)
			(layers "F.Cu" "F.Mask" "F.Paste")
			(net "USB_EN_4")
		)
		(pad "21" smd rect
			(at -0.999998 2.8702 90)
			(size 0.3048 1.27)
			(layers "F.Cu" "F.Mask" "F.Paste")
			(net "USB_OCS_N4")
		)
		(pad "22" smd rect
			(at -0.500126 2.8702 90)
			(size 0.3048 1.27)
			(layers "F.Cu" "F.Mask" "F.Paste")
			(net "TP_USB_SDA")
		)
		(pad "23" smd rect
			(at 0 2.8702 90)
			(size 0.3048 1.27)
			(layers "F.Cu" "F.Mask" "F.Paste")
			(net "P3V3_STBY")
		)
		(pad "24" smd rect
			(at 0.500126 2.8702 90)
			(size 0.3048 1.27)
			(layers "F.Cu" "F.Mask" "F.Paste")
			(net "CFG_SEL0")
		)
		(pad "25" smd rect
			(at 0.999998 2.8702 90)
			(size 0.3048 1.27)
			(layers "F.Cu" "F.Mask" "F.Paste")
			(net "CFG_SEL1")
		)
		(pad "26" smd rect
			(at 1.500124 2.8702 90)
			(size 0.3048 1.27)
			(layers "F.Cu" "F.Mask" "F.Paste")
			(net "USB_RESET_N")
		)
		(pad "27" smd rect
			(at 1.999996 2.9591 90)
			(size 0.3048 1.0922)
			(layers "F.Cu" "F.Mask" "F.Paste")
			(net "VBUS_DET")
		)
		(pad "28" smd rect
			(at 2.9591 1.999996 90)
			(size 1.0922 0.3048)
			(layers "F.Cu" "F.Mask" "F.Paste")
			(net "USB_SUSP_IND")
		)
		(pad "29" smd rect
			(at 2.8702 1.500124 90)
			(size 1.27 0.3048)
			(layers "F.Cu" "F.Mask" "F.Paste")
			(net "P3V3_STBY")
		)
		(pad "30" smd rect
			(at 2.8702 0.999998 90)
			(size 1.27 0.3048)
			(layers "F.Cu" "F.Mask" "F.Paste")
			(net "USB_COMP_DN")
		)
		(pad "31" smd rect
			(at 2.8702 0.500126 90)
			(size 1.27 0.3048)
			(layers "F.Cu" "F.Mask" "F.Paste")
			(net "USB_COMP_DP")
		)
		(pad "32" smd rect
			(at 2.8702 0 90)
			(size 1.27 0.3048)
			(layers "F.Cu" "F.Mask" "F.Paste")
			(net "USB_HUB_XTAL_OUT")
		)
		(pad "33" smd rect
			(at 2.8702 -0.500126 90)
			(size 1.27 0.3048)
			(layers "F.Cu" "F.Mask" "F.Paste")
			(net "USB_HUB_XTAL_IN")
		)
		(pad "34" smd rect
			(at 2.8702 -0.999998 90)
			(size 1.27 0.3048)
			(layers "F.Cu" "F.Mask" "F.Paste")
			(net "PLLFILT")
		)
		(pad "35" smd rect
			(at 2.8702 -1.500124 90)
			(size 1.27 0.3048)
			(layers "F.Cu" "F.Mask" "F.Paste")
			(net "RBIAS")
		)
		(pad "36" smd rect
			(at 2.9591 -1.999996 90)
			(size 1.0922 0.3048)
			(layers "F.Cu" "F.Mask" "F.Paste")
			(net "P3V3_STBY")
		)
		(pad "37" smd rect
			(at 0 0 90)
			(size 3.8608 3.8608)
			(layers "F.Cu" "F.Mask" "F.Paste")
			(net "GND")
		)
	)
	(footprint ""
		(layer "F.Cu")
		(at 88.362028 -69.285612)
		(property "Reference" "R15"
			(at 0 0 0)
			(layer "F.SilkS")
			(hide yes)
			(effects
				(font
					(size 1.27 1.27)
				)
			)
		)
		(property "Value" "0R2J-2-GP"
			(at 0.064008 -3.993896 0)
			(unlocked yes)
			(layer "F.Fab")
			(hide yes)
			(effects
				(font
					(size 1.016 1.016)
					(thickness 0.1524)
				)
			)
		)
		(property "Device Type" "R402H16"
			(at 0.064008 -5.517896 0)
			(unlocked yes)
			(layer "F.Fab")
			(hide yes)
			(effects
				(font
					(size 1.016 1.016)
					(thickness 0.1524)
				)
			)
		)
		(duplicate_pad_numbers_are_jumpers no)
		(fp_line
			(start -0.508 -0.9398)
			(end -0.508 0.9398)
			(stroke
				(width 0.1524)
				(type default)
			)
			(layer "F.SilkS")
		)
		(fp_line
			(start 0.508 -0.9398)
			(end -0.508 -0.9398)
			(stroke
				(width 0.1524)
				(type default)
			)
			(layer "F.SilkS")
		)
		(fp_rect
			(start -0.508 0.9398)
			(end 0.508 -0.9398)
			(stroke
				(width 0)
				(type default)
			)
			(fill no)
			(layer "F.CrtYd")
		)
		(fp_rect
			(start -0.508 0.9398)
			(end 0.508 -0.9398)
			(stroke
				(width 0)
				(type default)
			)
			(fill no)
			(layer "F.Fab")
		)
		(pad "1" smd custom
			(at 0 -0.4445)
			(size 0.1397 0.1397)
			(layers "F.Cu" "F.Mask" "F.Paste")
			(net "NCSI_RXD1")
			(options
				(clearance outline)
				(anchor circle)
			)
			(primitives
				(gr_poly
					(pts
						(arc
							(start -0.1778 -0.2794)
							(mid -0.249642 -0.249642)
							(end -0.2794 -0.1778)
						)
						(arc
							(start -0.2794 0.1778)
							(mid -0.249642 0.249642)
							(end -0.1778 0.2794)
						)
						(arc
							(start 0.1778 0.2794)
							(mid 0.249642 0.249642)
							(end 0.2794 0.1778)
						)
						(arc
							(start 0.2794 -0.1778)
							(mid 0.249642 -0.249642)
							(end 0.1778 -0.2794)
						)
					)
					(width 0)
					(fill yes)
				)
			)
		)
		(pad "2" smd custom
			(at 0 0.4445)
			(size 0.1397 0.1397)
			(layers "F.Cu" "F.Mask" "F.Paste")
			(net "NCSI_RXD1_R")
			(options
				(clearance outline)
				(anchor circle)
			)
			(primitives
				(gr_poly
					(pts
						(arc
							(start -0.1778 -0.2794)
							(mid -0.249642 -0.249642)
							(end -0.2794 -0.1778)
						)
						(arc
							(start -0.2794 0.1778)
							(mid -0.249642 0.249642)
							(end -0.1778 0.2794)
						)
						(arc
							(start 0.1778 0.2794)
							(mid 0.249642 0.249642)
							(end 0.2794 0.1778)
						)
						(arc
							(start 0.2794 -0.1778)
							(mid 0.249642 -0.249642)
							(end 0.1778 -0.2794)
						)
					)
					(width 0)
					(fill yes)
				)
			)
		)
	)
	(footprint ""
		(layer "F.Cu")
		(at 93.72092 -62.359032 90)
		(property "Reference" "R502"
			(at 0 0 90)
			(layer "F.SilkS")
			(hide yes)
			(effects
				(font
					(size 1.27 1.27)
				)
			)
		)
		(property "Value" "2K2R2J-2-GP"
			(at 0.064008 -3.993896 90)
			(unlocked yes)
			(layer "F.Fab")
			(hide yes)
			(effects
				(font
					(size 1.016 1.016)
					(thickness 0.1524)
				)
			)
		)
		(property "Device Type" "R402H16"
			(at 0.064008 -5.517896 90)
			(unlocked yes)
			(layer "F.Fab")
			(hide yes)
			(effects
				(font
					(size 1.016 1.016)
					(thickness 0.1524)
				)
			)
		)
		(duplicate_pad_numbers_are_jumpers no)
		(fp_line
			(start 0.508 -0.9398)
			(end -0.508 -0.9398)
			(stroke
				(width 0.1524)
				(type default)
			)
			(layer "F.SilkS")
		)
		(fp_line
			(start -0.508 -0.9398)
			(end -0.508 0.9398)
			(stroke
				(width 0.1524)
				(type default)
			)
			(layer "F.SilkS")
		)
		(fp_rect
			(start -0.508 0.9398)
			(end 0.508 -0.9398)
			(stroke
				(width 0)
				(type default)
			)
			(fill no)
			(layer "F.CrtYd")
		)
		(fp_rect
			(start -0.508 0.9398)
			(end 0.508 -0.9398)
			(stroke
				(width 0)
				(type default)
			)
			(fill no)
			(layer "F.Fab")
		)
		(pad "1" smd custom
			(at 0 -0.4445 90)
			(size 0.1397 0.1397)
			(layers "F.Cu" "F.Mask" "F.Paste")
			(net "P3V3_STBY")
			(options
				(clearance outline)
				(anchor circle)
			)
			(primitives
				(gr_poly
					(pts
						(arc
							(start -0.1778 -0.2794)
							(mid -0.249642 -0.249642)
							(end -0.2794 -0.1778)
						)
						(arc
							(start -0.2794 0.1778)
							(mid -0.249642 0.249642)
							(end -0.1778 0.2794)
						)
						(arc
							(start 0.1778 0.2794)
							(mid 0.249642 0.249642)
							(end 0.2794 0.1778)
						)
						(arc
							(start 0.2794 -0.1778)
							(mid 0.249642 -0.249642)
							(end 0.1778 -0.2794)
						)
					)
					(width 0)
					(fill yes)
				)
			)
		)
		(pad "2" smd custom
			(at 0 0.4445 90)
			(size 0.1397 0.1397)
			(layers "F.Cu" "F.Mask" "F.Paste")
			(net "IOM_FULL_PWR_EN")
			(options
				(clearance outline)
				(anchor circle)
			)
			(primitives
				(gr_poly
					(pts
						(arc
							(start -0.1778 -0.2794)
							(mid -0.249642 -0.249642)
							(end -0.2794 -0.1778)
						)
						(arc
							(start -0.2794 0.1778)
							(mid -0.249642 0.249642)
							(end -0.1778 0.2794)
						)
						(arc
							(start 0.1778 0.2794)
							(mid 0.249642 0.249642)
							(end 0.2794 0.1778)
						)
						(arc
							(start 0.2794 -0.1778)
							(mid 0.249642 -0.249642)
							(end 0.1778 -0.2794)
						)
					)
					(width 0)
					(fill yes)
				)
			)
		)
	)
	(footprint ""
		(layer "F.Cu")
		(at 212.085936 -94.683326)
		(property "Reference" "R840"
			(at 0 0 0)
			(layer "F.SilkS")
			(hide yes)
			(effects
				(font
					(size 1.27 1.27)
				)
			)
		)
		(property "Value" "44K2R2F-1-GP"
			(at 0.064008 -3.993896 0)
			(unlocked yes)
			(layer "F.Fab")
			(hide yes)
			(effects
				(font
					(size 1.016 1.016)
					(thickness 0.1524)
				)
			)
		)
		(property "Device Type" "R402H16"
			(at 0.064008 -5.517896 0)
			(unlocked yes)
			(layer "F.Fab")
			(hide yes)
			(effects
				(font
					(size 1.016 1.016)
					(thickness 0.1524)
				)
			)
		)
		(duplicate_pad_numbers_are_jumpers no)
		(fp_line
			(start -0.508 -0.9398)
			(end -0.508 0.9398)
			(stroke
				(width 0.1524)
				(type default)
			)
			(layer "F.SilkS")
		)
		(fp_line
			(start 0.508 -0.9398)
			(end -0.508 -0.9398)
			(stroke
				(width 0.1524)
				(type default)
			)
			(layer "F.SilkS")
		)
		(fp_rect
			(start -0.508 0.9398)
			(end 0.508 -0.9398)
			(stroke
				(width 0)
				(type default)
			)
			(fill no)
			(layer "F.CrtYd")
		)
		(fp_rect
			(start -0.508 0.9398)
			(end 0.508 -0.9398)
			(stroke
				(width 0)
				(type default)
			)
			(fill no)
			(layer "F.Fab")
		)
		(pad "1" smd custom
			(at 0 -0.4445)
			(size 0.1397 0.1397)
			(layers "F.Cu" "F.Mask" "F.Paste")
			(net "P3V3_M2_VFB")
			(options
				(clearance outline)
				(anchor circle)
			)
			(primitives
				(gr_poly
					(pts
						(arc
							(start -0.1778 -0.2794)
							(mid -0.249642 -0.249642)
							(end -0.2794 -0.1778)
						)
						(arc
							(start -0.2794 0.1778)
							(mid -0.249642 0.249642)
							(end -0.1778 0.2794)
						)
						(arc
							(start 0.1778 0.2794)
							(mid 0.249642 0.249642)
							(end 0.2794 0.1778)
						)
						(arc
							(start 0.2794 -0.1778)
							(mid 0.249642 -0.249642)
							(end 0.1778 -0.2794)
						)
					)
					(width 0)
					(fill yes)
				)
			)
		)
		(pad "2" smd custom
			(at 0 0.4445)
			(size 0.1397 0.1397)
			(layers "F.Cu" "F.Mask" "F.Paste")
			(net "P3V3_M2_VFB_R")
			(options
				(clearance outline)
				(anchor circle)
			)
			(primitives
				(gr_poly
					(pts
						(arc
							(start -0.1778 -0.2794)
							(mid -0.249642 -0.249642)
							(end -0.2794 -0.1778)
						)
						(arc
							(start -0.2794 0.1778)
							(mid -0.249642 0.249642)
							(end -0.1778 0.2794)
						)
						(arc
							(start 0.1778 0.2794)
							(mid 0.249642 0.249642)
							(end 0.2794 0.1778)
						)
						(arc
							(start 0.2794 -0.1778)
							(mid 0.249642 -0.249642)
							(end 0.1778 -0.2794)
						)
					)
					(width 0)
					(fill yes)
				)
			)
		)
	)
)
